(kicad_pcb
	(version 20260206)
	(generator "pcbnew")
	(generator_version "10.0")
	(general
		(thickness 1.21888)
		(legacy_teardrops no)
	)
	(paper "A4")
	(title_block
		(title "timecard-v8 — TimeCard-DC-V8_EXP.PcbDoc")
		(comment 1 "Time Appliance Project (Time Card) / footprints 18-29 of 288")
	)
	(layers
		(0 "F.Cu" signal "TOP")
		(4 "In1.Cu" signal "SGND")
		(6 "In2.Cu" signal "IN1")
		(8 "In3.Cu" signal "IN2")
		(10 "In4.Cu" signal "SGND1")
		(2 "B.Cu" signal "BOTTOM")
		(9 "F.Adhes" user "F.Adhesive")
		(11 "B.Adhes" user "B.Adhesive")
		(13 "F.Paste" user "Top Paste")
		(15 "B.Paste" user "Bottom Paste")
		(5 "F.SilkS" user "Top Overlay")
		(7 "B.SilkS" user "Bottom Overlay")
		(1 "F.Mask" user "Top Solder")
		(3 "B.Mask" user "Bottom Solder")
		(17 "Dwgs.User" user "User.Drawings")
		(19 "Cmts.User" user "User.Comments")
		(21 "Eco1.User" user "User.Eco1")
		(23 "Eco2.User" user "User.Eco2")
		(25 "Edge.Cuts" user)
		(27 "Margin" user)
		(31 "F.CrtYd" user "Top Courtyard")
		(29 "B.CrtYd" user "Bottom Courtyard")
		(35 "F.Fab" user "Top Component Center")
		(33 "B.Fab" user "Bottom Component Center")
	)
	(footprint "Vault:RESC1608X55X25NL10T15"
		(layer "F.Cu")
		(at 77.5761 135.6162 180)
		(property "Reference" "R34"
			(at -0.2286 1.473079 0)
			(unlocked yes)
			(layer "F.SilkS")
			(effects
				(font
					(size 0.762 0.762)
					(thickness 0.2286)
				)
			)
		)
		(property "Value" "49.9R"
			(at -2.884671 3.186595 90)
			(unlocked yes)
			(layer "F.SilkS")
			(hide yes)
			(effects
				(font
					(size 0.762 0.762)
					(thickness 0.2286)
				)
			)
		)
		(sheetname "USER_IO")
		(sheetfile "USER_IO.kicad_sch")
		(duplicate_pad_numbers_are_jumpers no)
		(pad "1" smd rect
			(at -0.7 0 270)
			(size 0.9 0.7)
			(layers "F.Cu" "F.Mask" "F.Paste")
			(net "NetR34_1")
		)
		(pad "2" smd rect
			(at 0.7 0 270)
			(size 0.9 0.7)
			(layers "F.Cu" "F.Mask" "F.Paste")
			(net "NetAN4_1")
		)
	)
	(footprint "SamacSys:155124M173200"
		(layer "F.Cu")
		(at 58.4511 82.6662 90)
		(property "Reference" "D14"
			(at -4.7 -0.231655 90)
			(unlocked yes)
			(layer "F.SilkS")
			(effects
				(font
					(size 0.762 0.762)
					(thickness 0.2286)
				)
				(justify left bottom)
			)
		)
		(property "Value" "155124M173200"
			(at -4.043045 -0.5715 0)
			(unlocked yes)
			(layer "F.SilkS")
			(hide yes)
			(effects
				(font
					(size 0.762 0.762)
					(thickness 0.2286)
				)
				(justify left bottom)
			)
		)
		(sheetname "USER_IO_STATUS")
		(sheetfile "USER_IO_STATUS.kicad_sch")
		(duplicate_pad_numbers_are_jumpers no)
		(fp_line
			(start -0.8 0.5)
			(end 0.8 0.5)
			(stroke
				(width 0.1)
				(type solid)
			)
			(layer "F.SilkS")
		)
		(fp_arc
			(start -2 -0.1)
			(mid -1.95 -0.05)
			(end -2 0)
			(stroke
				(width 0.1)
				(type solid)
			)
			(layer "F.SilkS")
		)
		(fp_arc
			(start -2 0)
			(mid -2.05 -0.05)
			(end -2 -0.1)
			(stroke
				(width 0.1)
				(type solid)
			)
			(layer "F.SilkS")
		)
		(pad "1" smd rect
			(at -1.4 0 180)
			(size 0.9 0.6)
			(layers "F.Cu" "F.Mask" "F.Paste")
			(net "+3.3V")
		)
		(pad "2" smd rect
			(at -0.45 -0.325 90)
			(size 0.6 0.55)
			(layers "F.Cu" "F.Mask" "F.Paste")
			(net "NetD14_2")
		)
		(pad "3" smd rect
			(at 0.45 -0.325 90)
			(size 0.6 0.55)
			(layers "F.Cu" "F.Mask" "F.Paste")
			(net "NetD14_3")
		)
		(pad "4" smd rect
			(at 1.4 0 180)
			(size 0.9 0.6)
			(layers "F.Cu" "F.Mask" "F.Paste")
			(net "NetD14_4")
		)
	)
	(footprint "Vault:RESC1609X50X30NL10T20"
		(layer "F.Cu")
		(at 113.8761 84.8286 -90)
		(property "Reference" "R12"
			(at 2.2714 -0.026931 90)
			(unlocked yes)
			(layer "F.SilkS")
			(effects
				(font
					(size 0.762 0.762)
					(thickness 0.2286)
				)
			)
		)
		(property "Value" "110R"
			(at -2.884671 2.24708 180)
			(unlocked yes)
			(layer "F.SilkS")
			(hide yes)
			(effects
				(font
					(size 0.762 0.762)
					(thickness 0.2286)
				)
			)
		)
		(sheetname "MAC")
		(sheetfile "MAC.kicad_sch")
		(duplicate_pad_numbers_are_jumpers no)
		(pad "1" smd rect
			(at -0.625 0)
			(size 0.95 0.8)
			(layers "F.Cu" "F.Mask" "F.Paste")
			(net "MAC_PPS_OUT-")
		)
		(pad "2" smd rect
			(at 0.625 0)
			(size 0.95 0.8)
			(layers "F.Cu" "F.Mask" "F.Paste")
			(net "MAC_PPS_OUT+")
		)
	)
	(footprint "Vault:RESC1005X40X25NL05T05"
		(layer "F.Cu")
		(at 211.3261 75.6162)
		(property "Reference" "R102"
			(at 0.1286 -0.973079 0)
			(unlocked yes)
			(layer "F.SilkS")
			(effects
				(font
					(size 0.762 0.762)
					(thickness 0.2286)
				)
			)
		)
		(property "Value" "DNI_27_1%_0402"
			(at -2.732271 10.296375 270)
			(unlocked yes)
			(layer "F.SilkS")
			(hide yes)
			(effects
				(font
					(size 0.762 0.762)
					(thickness 0.2286)
				)
			)
		)
		(sheetname "USBUart_DipSelects")
		(sheetfile "USBUart_DipSelects.kicad_sch")
		(duplicate_pad_numbers_are_jumpers no)
		(pad "1" smd rect
			(at -0.45 0 90)
			(size 0.55 0.55)
			(layers "F.Cu" "F.Mask" "F.Paste")
			(net "GPS2_TX_FPGA")
		)
		(pad "2" smd rect
			(at 0.45 0 90)
			(size 0.55 0.55)
			(layers "F.Cu" "F.Mask" "F.Paste")
			(net "GPS2_TX")
		)
	)
	(footprint "Vault:RESC3116X65X50ML20T20"
		(layer "F.Cu")
		(at 155.9123 86.8162)
		(property "Reference" "R45"
			(at 4.0286 0.026931 0)
			(unlocked yes)
			(layer "F.SilkS")
			(effects
				(font
					(size 0.762 0.762)
					(thickness 0.2286)
				)
			)
		)
		(property "Value" "0_5%_1206"
			(at 4.35396 3.291071 0)
			(unlocked yes)
			(layer "F.SilkS")
			(hide yes)
			(effects
				(font
					(size 0.762 0.762)
					(thickness 0.2286)
				)
			)
		)
		(sheetname "MAC")
		(sheetfile "MAC.kicad_sch")
		(duplicate_pad_numbers_are_jumpers no)
		(fp_line
			(start -0.35 -0.85)
			(end 0.35 -0.85)
			(stroke
				(width 0.2)
				(type solid)
			)
			(layer "F.SilkS")
		)
		(fp_line
			(start -0.35 0.85)
			(end 0.35 0.85)
			(stroke
				(width 0.2)
				(type solid)
			)
			(layer "F.SilkS")
		)
		(pad "1" smd rect
			(at -1.475 0 90)
			(size 1.9 1.45)
			(layers "F.Cu" "F.Mask" "F.Paste")
			(net "MAC_VCC")
		)
		(pad "2" smd rect
			(at 1.475 0 90)
			(size 1.9 1.45)
			(layers "F.Cu" "F.Mask" "F.Paste")
			(net "+5.0V")
		)
	)
	(footprint "Passives:FUSM1608X60N"
		(layer "F.Cu")
		(at 214.2261 95.6162 180)
		(property "Reference" "F1"
			(at 1.2 0.706655 0)
			(unlocked yes)
			(layer "F.SilkS")
			(effects
				(font
					(size 0.762 0.762)
					(thickness 0.2286)
				)
				(justify left bottom)
			)
		)
		(property "Value" "FUSE_0603_5.00A"
			(at 2.1929 -4.987045 0)
			(unlocked yes)
			(layer "F.SilkS")
			(hide yes)
			(effects
				(font
					(size 0.762 0.762)
					(thickness 0.2286)
				)
				(justify left bottom)
			)
		)
		(sheetname "POWER")
		(sheetfile "POWER.kicad_sch")
		(duplicate_pad_numbers_are_jumpers no)
		(fp_line
			(start 0 -0.5)
			(end 0 0.5)
			(stroke
				(width 0.1524)
				(type solid)
			)
			(layer "F.SilkS")
		)
		(pad "1" smd rect
			(at -0.69 0 270)
			(size 1 0.72)
			(layers "F.Cu" "F.Mask" "F.Paste")
			(net "NetD12_1")
		)
		(pad "2" smd rect
			(at 0.69 0 270)
			(size 1 0.72)
			(layers "F.Cu" "F.Mask" "F.Paste")
			(net "+12V_SENS")
		)
	)
	(footprint "Vault:FP-0402-L_1_0_0_05-W_0_5-IPC_C"
		(layer "F.Cu")
		(at 189.8261 83.0162)
		(property "Reference" "C65"
			(at 0.1286 -1.873079 0)
			(unlocked yes)
			(layer "F.SilkS")
			(effects
				(font
					(size 0.762 0.762)
					(thickness 0.2286)
				)
			)
		)
		(property "Value" "1uF_0402"
			(at -2.795791 1.459885 270)
			(unlocked yes)
			(layer "F.SilkS")
			(hide yes)
			(effects
				(font
					(size 0.762 0.762)
					(thickness 0.2286)
				)
			)
		)
		(sheetname "GPS_IMU_SENSORS")
		(sheetfile "GPS_IMU_SENSORS.kicad_sch")
		(duplicate_pad_numbers_are_jumpers no)
		(fp_line
			(start -0.63624 -0.675)
			(end 0.63624 -0.675)
			(stroke
				(width 0.2)
				(type solid)
			)
			(layer "F.SilkS")
		)
		(fp_line
			(start -0.63624 0.675)
			(end 0.63624 0.675)
			(stroke
				(width 0.2)
				(type solid)
			)
			(layer "F.SilkS")
		)
		(fp_line
			(start -0.73624 -0.375)
			(end 0.73624 -0.375)
			(stroke
				(width 0.2)
				(type solid)
			)
			(layer "F.CrtYd")
		)
		(fp_line
			(start -0.73624 0.375)
			(end -0.73624 -0.375)
			(stroke
				(width 0.2)
				(type solid)
			)
			(layer "F.CrtYd")
		)
		(fp_line
			(start -0.73624 0.375)
			(end 0.73624 0.375)
			(stroke
				(width 0.2)
				(type solid)
			)
			(layer "F.CrtYd")
		)
		(fp_line
			(start 0.73624 0.375)
			(end 0.73624 -0.375)
			(stroke
				(width 0.2)
				(type solid)
			)
			(layer "F.CrtYd")
		)
		(fp_line
			(start -0.73624 -0.375)
			(end 0.73624 -0.375)
			(stroke
				(width 0.2)
				(type solid)
			)
			(layer "F.Fab")
		)
		(fp_line
			(start -0.73624 0.375)
			(end -0.73624 -0.375)
			(stroke
				(width 0.2)
				(type solid)
			)
			(layer "F.Fab")
		)
		(fp_line
			(start -0.73624 0.375)
			(end 0.73624 0.375)
			(stroke
				(width 0.2)
				(type solid)
			)
			(layer "F.Fab")
		)
		(fp_line
			(start -0.5 0)
			(end 0.5 0)
			(stroke
				(width 0.1)
				(type solid)
			)
			(layer "F.Fab")
		)
		(fp_line
			(start 0 0.5)
			(end 0 -0.5)
			(stroke
				(width 0.1)
				(type solid)
			)
			(layer "F.Fab")
		)
		(fp_line
			(start 0.73624 0.375)
			(end 0.73624 -0.375)
			(stroke
				(width 0.2)
				(type solid)
			)
			(layer "F.Fab")
		)
		(fp_text user "${REFERENCE}"
			(at -0.00001 0.09602 360)
			(unlocked yes)
			(layer "F.Fab")
			(effects
				(font
					(face "Arial")
					(size 0.63 0.63)
					(thickness 0.1)
				)
				(justify left bottom)
			)
		)
		(pad "1" smd rect
			(at -0.37856 0)
			(size 0.51535 0.47247)
			(layers "F.Cu" "F.Mask" "F.Paste")
			(net "NetC65_1")
			(solder_mask_margin 0)
			(solder_paste_margin 0)
		)
		(pad "2" smd rect
			(at 0.37856 0)
			(size 0.51535 0.47247)
			(layers "F.Cu" "F.Mask" "F.Paste")
			(net "GND")
			(solder_mask_margin 0)
			(solder_paste_margin 0)
		)
	)
	(footprint "Vault:RESC1005X40X25LL05T05"
		(layer "F.Cu")
		(at 171.0261 101.8162)
		(property "Reference" "R49"
			(at 2.4286 0.226931 0)
			(unlocked yes)
			(layer "F.SilkS")
			(effects
				(font
					(size 0.762 0.762)
					(thickness 0.2286)
				)
			)
		)
		(property "Value" "0_1%_0402"
			(at -2.579871 6.66536 270)
			(unlocked yes)
			(layer "F.SilkS")
			(hide yes)
			(effects
				(font
					(size 0.762 0.762)
					(thickness 0.2286)
				)
			)
		)
		(sheetname "FPGA")
		(sheetfile "FPGA.kicad_sch")
		(duplicate_pad_numbers_are_jumpers no)
		(pad "1" smd rect
			(at -0.4 0 90)
			(size 0.45 0.45)
			(layers "F.Cu" "F.Mask" "F.Paste")
			(net "MAC_FREQ_CTRL")
		)
		(pad "2" smd rect
			(at 0.4 0 90)
			(size 0.45 0.45)
			(layers "F.Cu" "F.Mask" "F.Paste")
			(net "NetJ35_33")
		)
	)
	(footprint "Vault:RESC1608X55X30NL15T15"
		(layer "F.Cu")
		(at 82.1261 139.6162 -90)
		(property "Reference" "R32"
			(at 2.7714 -0.026921 90)
			(unlocked yes)
			(layer "F.SilkS")
			(effects
				(font
					(size 0.762 0.762)
					(thickness 0.2286)
				)
			)
		)
		(property "Value" "4.7K"
			(at -3.087871 2.37404 180)
			(unlocked yes)
			(layer "F.SilkS")
			(hide yes)
			(effects
				(font
					(size 0.762 0.762)
					(thickness 0.2286)
				)
			)
		)
		(sheetname "USER_IO")
		(sheetfile "USER_IO.kicad_sch")
		(duplicate_pad_numbers_are_jumpers no)
		(pad "1" smd rect
			(at -0.75 0)
			(size 0.95 0.95)
			(layers "F.Cu" "F.Mask" "F.Paste")
			(net "ANT4_IO_IN")
		)
		(pad "2" smd rect
			(at 0.75 0)
			(size 0.95 0.95)
			(layers "F.Cu" "F.Mask" "F.Paste")
			(net "+3.3V")
		)
	)
	(footprint "Vault:RESC1608X55X30NL15T15"
		(layer "F.Cu")
		(at 101.6261 82.9162)
		(property "Reference" "R26"
			(at 3.14763 0.055781 0)
			(unlocked yes)
			(layer "F.SilkS")
			(effects
				(font
					(size 0.762 0.762)
					(thickness 0.2286)
				)
			)
		)
		(property "Value" "4.7K"
			(at -3.087881 2.37404 270)
			(unlocked yes)
			(layer "F.SilkS")
			(hide yes)
			(effects
				(font
					(size 0.762 0.762)
					(thickness 0.2286)
				)
			)
		)
		(sheetname "GPS_IMU_SENSORS")
		(sheetfile "GPS_IMU_SENSORS.kicad_sch")
		(duplicate_pad_numbers_are_jumpers no)
		(pad "1" smd rect
			(at -0.75 0 90)
			(size 0.95 0.95)
			(layers "F.Cu" "F.Mask" "F.Paste")
			(net "SDA")
		)
		(pad "2" smd rect
			(at 0.75 0 90)
			(size 0.95 0.95)
			(layers "F.Cu" "F.Mask" "F.Paste")
			(net "+3.3V")
		)
	)
	(footprint "Vault:FP-0402-L_1_0_1-W_0_5_0_1-IPC_C"
		(layer "F.Cu")
		(at 226.1261 125.7162 180)
		(property "Reference" "C83"
			(at 1.6714 -0.026931 0)
			(unlocked yes)
			(layer "F.SilkS")
			(effects
				(font
					(size 0.762 0.762)
					(thickness 0.2286)
				)
			)
		)
		(property "Value" "0.1uF_25V_0402"
			(at -2.465551 9.839215 90)
			(unlocked yes)
			(layer "F.SilkS")
			(hide yes)
			(effects
				(font
					(size 0.762 0.762)
					(thickness 0.2286)
				)
			)
		)
		(sheetname "POWER")
		(sheetfile "POWER.kicad_sch")
		(duplicate_pad_numbers_are_jumpers no)
		(fp_line
			(start 0.65607 0.7)
			(end -0.65607 0.7)
			(stroke
				(width 0.2)
				(type solid)
			)
			(layer "F.SilkS")
		)
		(fp_line
			(start 0.65607 -0.7)
			(end -0.65607 -0.7)
			(stroke
				(width 0.2)
				(type solid)
			)
			(layer "F.SilkS")
		)
		(fp_line
			(start 0.75607 0.4)
			(end -0.75606 0.4)
			(stroke
				(width 0.2)
				(type solid)
			)
			(layer "F.CrtYd")
		)
		(fp_line
			(start 0.75607 -0.4)
			(end 0.75607 0.4)
			(stroke
				(width 0.2)
				(type solid)
			)
			(layer "F.CrtYd")
		)
		(fp_line
			(start 0.75607 -0.4)
			(end -0.75606 -0.4)
			(stroke
				(width 0.2)
				(type solid)
			)
			(layer "F.CrtYd")
		)
		(fp_line
			(start -0.75606 -0.4)
			(end -0.75606 0.4)
			(stroke
				(width 0.2)
				(type solid)
			)
			(layer "F.CrtYd")
		)
		(fp_line
			(start 0.75607 0.4)
			(end -0.75606 0.4)
			(stroke
				(width 0.2)
				(type solid)
			)
			(layer "F.Fab")
		)
		(fp_line
			(start 0.75607 -0.4)
			(end 0.75607 0.4)
			(stroke
				(width 0.2)
				(type solid)
			)
			(layer "F.Fab")
		)
		(fp_line
			(start 0.75607 -0.4)
			(end -0.75606 -0.4)
			(stroke
				(width 0.2)
				(type solid)
			)
			(layer "F.Fab")
		)
		(fp_line
			(start 0.5 0)
			(end -0.5 0)
			(stroke
				(width 0.1)
				(type solid)
			)
			(layer "F.Fab")
		)
		(fp_line
			(start 0 -0.5)
			(end 0 0.5)
			(stroke
				(width 0.1)
				(type solid)
			)
			(layer "F.Fab")
		)
		(fp_line
			(start -0.75606 -0.4)
			(end -0.75606 0.4)
			(stroke
				(width 0.2)
				(type solid)
			)
			(layer "F.Fab")
		)
		(fp_text user "${REFERENCE}"
			(at -0.00001 0.09601 180)
			(unlocked yes)
			(layer "F.Fab")
			(effects
				(font
					(face "Arial")
					(size 0.63 0.63)
					(thickness 0.1)
				)
				(justify left bottom)
			)
		)
		(pad "1" smd rect
			(at -0.36553 0 180)
			(size 0.58106 0.51213)
			(layers "F.Cu" "F.Mask" "F.Paste")
			(net "+3.3V")
			(solder_mask_margin 0)
			(solder_paste_margin 0)
		)
		(pad "2" smd rect
			(at 0.36554 0 180)
			(size 0.58106 0.51213)
			(layers "F.Cu" "F.Mask" "F.Paste")
			(net "GND")
			(solder_mask_margin 0)
			(solder_paste_margin 0)
		)
	)
	(footprint "Vault:FP-GRM31C-0_2-e0_3_0_8-IPC_C"
		(layer "F.Cu")
		(at 216.9261 119.6162 90)
		(property "Reference" "C76"
			(at 0.46924 -2.601729 90)
			(unlocked yes)
			(layer "F.SilkS")
			(effects
				(font
					(size 0.762 0.762)
					(thickness 0.2286)
				)
			)
		)
		(property "Value" "4.7uF_50V_1206"
			(at 8.594615 2.719551 90)
			(unlocked yes)
			(layer "F.SilkS")
			(hide yes)
			(effects
				(font
					(size 0.762 0.762)
					(thickness 0.2286)
				)
			)
		)
		(sheetname "POWER")
		(sheetfile "POWER.kicad_sch")
		(duplicate_pad_numbers_are_jumpers no)
		(fp_line
			(start -0.39847 -0.9)
			(end 0.39847 -0.9)
			(stroke
				(width 0.2)
				(type solid)
			)
			(layer "F.SilkS")
		)
		(fp_line
			(start -0.39847 0.9)
			(end 0.39847 0.9)
			(stroke
				(width 0.2)
				(type solid)
			)
			(layer "F.SilkS")
		)
		(fp_line
			(start 1.9531 -1)
			(end 1.9531 1)
			(stroke
				(width 0.2)
				(type solid)
			)
			(layer "F.CrtYd")
		)
		(fp_line
			(start -1.9531 -1)
			(end 1.9531 -1)
			(stroke
				(width 0.2)
				(type solid)
			)
			(layer "F.CrtYd")
		)
		(fp_line
			(start -1.9531 -1)
			(end -1.9531 1)
			(stroke
				(width 0.2)
				(type solid)
			)
			(layer "F.CrtYd")
		)
		(fp_line
			(start -1.9531 1)
			(end 1.9531 1)
			(stroke
				(width 0.2)
				(type solid)
			)
			(layer "F.CrtYd")
		)
		(fp_line
			(start 1.9531 -1)
			(end 1.9531 1)
			(stroke
				(width 0.2)
				(type solid)
			)
			(layer "F.Fab")
		)
		(fp_line
			(start -1.9531 -1)
			(end 1.9531 -1)
			(stroke
				(width 0.2)
				(type solid)
			)
			(layer "F.Fab")
		)
		(fp_line
			(start -1.9531 -1)
			(end -1.9531 1)
			(stroke
				(width 0.2)
				(type solid)
			)
			(layer "F.Fab")
		)
		(fp_line
			(start 0 -0.5)
			(end 0 0.5)
			(stroke
				(width 0.1)
				(type solid)
			)
			(layer "F.Fab")
		)
		(fp_line
			(start -0.5 0)
			(end 0.5 0)
			(stroke
				(width 0.1)
				(type solid)
			)
			(layer "F.Fab")
		)
		(fp_line
			(start -1.9531 1)
			(end 1.9531 1)
			(stroke
				(width 0.2)
				(type solid)
			)
			(layer "F.Fab")
		)
		(fp_text user "${REFERENCE}"
			(at -0.00002 0.09601 90)
			(unlocked yes)
			(layer "F.Fab")
			(effects
				(font
					(face "Arial")
					(size 0.63 0.63)
					(thickness 0.1)
				)
				(justify left bottom)
			)
		)
		(pad "1" smd rect
			(at -1.27578 0 90)
			(size 1.15464 1.7062)
			(layers "F.Cu" "F.Mask" "F.Paste")
			(net "+12V")
			(solder_mask_margin 0)
			(solder_paste_margin 0)
		)
		(pad "2" smd rect
			(at 1.27578 0 90)
			(size 1.15464 1.7062)
			(layers "F.Cu" "F.Mask" "F.Paste")
			(net "GND")
			(solder_mask_margin 0)
			(solder_paste_margin 0)
		)
	)
)
